# T6G (Grand Teton) — schematic netlist excerpt (pin names and nets, part order shuffled) for the footprints in the layout excerpt that follows; sources: Cadence DE-HDL packaged netlist, KiCad conversion of 04192023_DAF0TMB3IC0_F0TG_MB_C_brd_V02_OCP.brd

PU57  MPQ8633BGLEC838Z  MPQ8633BGLE-C838-Z IC  pkg QFN14_4X3  page 209
  BST  = SW_PVDD18_S5_P0_BST
  AGND  = GND
  CS  = PVDD18_S5_P0_CS
  MODE  = PVDD18_S5_P0_MODE
  TRK_REF  = PVDD18_S5_P0_REF
  RGND  = PVDD18_S5_P0_RGND
  FB  = PVDD18_S5_P0_FB
  EN  = PVDD18_S5_P0_EN
  PGOOD  = PWRGD_PVDD18_S5_P0
  VIN1  = SW_P12V_AUX_PVDD18_S5_P0_FLT
  PGND  = GND
  VCC  = PVDD18_S5_P0_VCC
  SW  = SW_PVDD18_S5_P0_SW
  VIN2  = SW_P12V_AUX_PVDD18_S5_P0_FLT

R6217  Q_RES  10K 1% EMPTY  pkg 0402LF  page 176 : A = USB_CPU0_ADD_A0 ; B = GND

(kicad_pcb
	(version 20260206)
	(generator "pcbnew")
	(generator_version "10.0")
	(general
		(thickness 1.6)
		(legacy_teardrops no)
	)
	(paper "A4")
	(title_block
		(title "04192023_DAF0TMB3IC0_F0TG_MB_C_brd_V02_OCP.brd")
		(comment 1 "Grand Teton / footprints 1756-1757 of 8354")
	)
	(layers
		(0 "F.Cu" signal "TOP")
		(4 "In1.Cu" signal "GND")
		(6 "In2.Cu" signal "IN1")
		(8 "In3.Cu" signal "GND1")
		(10 "In4.Cu" signal "IN2")
		(12 "In5.Cu" signal "GND2")
		(14 "In6.Cu" signal "IN3")
		(16 "In7.Cu" signal "GND3")
		(18 "In8.Cu" signal "VCC")
		(20 "In9.Cu" signal "VCC1")
		(22 "In10.Cu" signal "GND4")
		(24 "In11.Cu" signal "IN4")
		(26 "In12.Cu" signal "GND5")
		(28 "In13.Cu" signal "IN5")
		(30 "In14.Cu" signal "GND6")
		(32 "In15.Cu" signal "IN6")
		(34 "In16.Cu" signal "GND7")
		(2 "B.Cu" signal "BOTTOM")
		(9 "F.Adhes" user "F.Adhesive")
		(11 "B.Adhes" user "B.Adhesive")
		(13 "F.Paste" user "Package Geometry/Pastemask Top")
		(15 "B.Paste" user "Package Geometry/Pastemask Bottom")
		(5 "F.SilkS" user "Ref Des/Silkscreen Top")
		(7 "B.SilkS" user "Ref Des/Silkscreen Bottom")
		(1 "F.Mask" user "Board Geometry/Soldermask Top")
		(3 "B.Mask" user "Board Geometry/Soldermask Bottom")
		(17 "Dwgs.User" user "User.Drawings")
		(19 "Cmts.User" user "User.Comments")
		(21 "Eco1.User" user "User.Eco1")
		(23 "Eco2.User" user "User.Eco2")
		(25 "Edge.Cuts" user "Board Geometry/Outline")
		(27 "Margin" user)
		(31 "F.CrtYd" user "Package Geometry/Place Bound Top")
		(29 "B.CrtYd" user "Package Geometry/Place Bound Bottom")
		(35 "F.Fab" user "Ref Des/Assembly Top")
		(33 "B.Fab" user "Ref Des/Assembly Bottom")
	)
	(footprint ""
		(layer "F.Cu")
		(at 335.514442 -140.870686)
		(property "Reference" "PU57"
			(at 0.5334 -3.094228 0)
			(unlocked yes)
			(layer "F.SilkS")
			(effects
				(font
					(size 0.7874 0.5842)
					(thickness 0.1524)
				)
				(justify left)
			)
		)
		(property "Value" ""
			(at 0 0 0)
			(layer "F.Fab")
			(effects
				(font
					(size 1.27 1.27)
				)
			)
		)
		(duplicate_pad_numbers_are_jumpers no)
		(fp_line
			(start -1.549908 -2.050034)
			(end -1.549908 -1.9812)
			(stroke
				(width 0.1524)
				(type default)
			)
			(layer "F.SilkS")
		)
		(fp_line
			(start -1.549908 1.9812)
			(end -1.549908 2.050034)
			(stroke
				(width 0.1524)
				(type default)
			)
			(layer "F.SilkS")
		)
		(fp_line
			(start -1.549908 2.050034)
			(end -0.5842 2.050034)
			(stroke
				(width 0.1524)
				(type default)
			)
			(layer "F.SilkS")
		)
		(fp_line
			(start -0.5842 -2.050034)
			(end -1.549908 -2.050034)
			(stroke
				(width 0.1524)
				(type default)
			)
			(layer "F.SilkS")
		)
		(fp_line
			(start 0 2.050034)
			(end 1.549908 2.050034)
			(stroke
				(width 0.1524)
				(type default)
			)
			(layer "F.SilkS")
		)
		(fp_line
			(start 1.549908 -2.050034)
			(end 0.5842 -2.050034)
			(stroke
				(width 0.1524)
				(type default)
			)
			(layer "F.SilkS")
		)
		(fp_line
			(start 1.549908 -1.9812)
			(end 1.549908 -2.050034)
			(stroke
				(width 0.1524)
				(type default)
			)
			(layer "F.SilkS")
		)
		(fp_poly
			(pts
				(xy -1.9304 -1.700022) (xy -2.594864 -1.36779) (xy -2.594864 -2.032254)
			)
			(stroke
				(width 0)
				(type default)
			)
			(fill yes)
			(layer "F.SilkS")
		)
		(fp_line
			(start -1.549908 -2.050034)
			(end -1.549908 2.050034)
			(stroke
				(width 0.1)
				(type default)
			)
			(layer "F.Fab")
		)
		(fp_line
			(start -1.549908 2.050034)
			(end 1.549908 2.050034)
			(stroke
				(width 0.1)
				(type default)
			)
			(layer "F.Fab")
		)
		(fp_line
			(start 1.549908 -2.050034)
			(end -1.549908 -2.050034)
			(stroke
				(width 0.1)
				(type default)
			)
			(layer "F.Fab")
		)
		(fp_line
			(start 1.549908 2.050034)
			(end 1.549908 -2.050034)
			(stroke
				(width 0.1)
				(type default)
			)
			(layer "F.Fab")
		)
		(fp_poly
			(pts
				(xy -2.9464 -2.208022) (xy -2.9464 -1.192022) (xy -1.9304 -1.700022)
			)
			(stroke
				(width 0)
				(type default)
			)
			(fill yes)
			(layer "F.Fab")
		)
		(pad "1" smd circle
			(at -1.35001 -1.700022)
			(size 0 0)
			(layers "F.Cu" "F.Mask" "F.Paste")
			(net "SW_PVDD18_S5_P0_BST")
		)
		(pad "2" smd rect
			(at -1.400048 -1.199896 90)
			(size 0.1778 0.8128)
			(layers "F.Cu" "F.Mask" "F.Paste")
			(net "GND")
		)
		(pad "3" smd rect
			(at -1.400048 -0.8001 90)
			(size 0.1778 0.8128)
			(layers "F.Cu" "F.Mask" "F.Paste")
			(net "PVDD18_S5_P0_CS")
		)
		(pad "4" smd rect
			(at -1.400048 -0.40005 90)
			(size 0.1778 0.8128)
			(layers "F.Cu" "F.Mask" "F.Paste")
			(net "PVDD18_S5_P0_MODE")
		)
		(pad "5" smd rect
			(at -1.400048 0 90)
			(size 0.1778 0.8128)
			(layers "F.Cu" "F.Mask" "F.Paste")
			(net "PVDD18_S5_P0_REF")
		)
		(pad "6" smd rect
			(at -1.400048 0.40005 90)
			(size 0.1778 0.8128)
			(layers "F.Cu" "F.Mask" "F.Paste")
			(net "PVDD18_S5_P0_RGND")
		)
		(pad "7" smd rect
			(at -1.400048 0.8001 90)
			(size 0.1778 0.8128)
			(layers "F.Cu" "F.Mask" "F.Paste")
			(net "PVDD18_S5_P0_FB")
		)
		(pad "8" smd rect
			(at -1.400048 1.199896 90)
			(size 0.1778 0.8128)
			(layers "F.Cu" "F.Mask" "F.Paste")
			(net "PVDD18_S5_P0_EN")
		)
		(pad "9" smd rect
			(at -1.400048 1.700022 90)
			(size 0.3048 0.8128)
			(layers "F.Cu" "F.Mask" "F.Paste")
			(net "PWRGD_PVDD18_S5_P0")
		)
		(pad "10" smd rect
			(at -0.299974 1.299972)
			(size 0.3048 2.0066)
			(layers "F.Cu" "F.Mask" "F.Paste")
			(net "SW_P12V_AUX_PVDD18_S5_P0_FLT")
		)
		(pad "11_18" smd circle
			(at 1.175004 0.275082)
			(size 0 0)
			(layers "F.Cu" "F.Mask" "F.Paste")
			(net "GND")
		)
		(pad "19" smd rect
			(at 1.400048 -1.700022 270)
			(size 0.3048 0.8128)
			(layers "F.Cu" "F.Mask" "F.Paste")
			(net "PVDD18_S5_P0_VCC")
		)
		(pad "20" smd rect
			(at 0.299974 -1.299972)
			(size 0.3048 2.0066)
			(layers "F.Cu" "F.Mask" "F.Paste")
			(net "SW_PVDD18_S5_P0_SW")
		)
		(pad "21" smd rect
			(at -0.299974 -1.299972)
			(size 0.3048 2.0066)
			(layers "F.Cu" "F.Mask" "F.Paste")
			(net "SW_P12V_AUX_PVDD18_S5_P0_FLT")
		)
	)
	(footprint ""
		(layer "F.Cu")
		(at 105.84561 -68.62191 180)
		(property "Reference" "R6217"
			(at 0 0 180)
			(layer "F.SilkS")
			(hide yes)
			(effects
				(font
					(size 1.27 1.27)
				)
			)
		)
		(property "Value" ""
			(at 0 0 180)
			(layer "F.Fab")
			(effects
				(font
					(size 1.27 1.27)
				)
			)
		)
		(duplicate_pad_numbers_are_jumpers no)
		(fp_line
			(start 0.7874 0.4064)
			(end -0.7874 0.4064)
			(stroke
				(width 0.1524)
				(type default)
			)
			(layer "F.SilkS")
		)
		(fp_line
			(start 0.7874 -0.4064)
			(end 0.7874 0.4064)
			(stroke
				(width 0.1524)
				(type default)
			)
			(layer "F.SilkS")
		)
		(fp_line
			(start -0.7874 0.4064)
			(end -0.7874 -0.4064)
			(stroke
				(width 0.1524)
				(type default)
			)
			(layer "F.SilkS")
		)
		(fp_line
			(start -0.7874 -0.4064)
			(end 0.7874 -0.4064)
			(stroke
				(width 0.1524)
				(type default)
			)
			(layer "F.SilkS")
		)
		(fp_line
			(start 0.67945 0.3048)
			(end 0.120396 0.3048)
			(stroke
				(width 0.1)
				(type default)
			)
			(layer "F.Fab")
		)
		(fp_line
			(start 0.67945 -0.3048)
			(end 0.67945 0.3048)
			(stroke
				(width 0.1)
				(type default)
			)
			(layer "F.Fab")
		)
		(fp_line
			(start 0.12065 -0.2794)
			(end 0.12065 -0.3048)
			(stroke
				(width 0.1)
				(type default)
			)
			(layer "F.Fab")
		)
		(fp_line
			(start 0.12065 -0.3048)
			(end 0.67945 -0.3048)
			(stroke
				(width 0.1)
				(type default)
			)
			(layer "F.Fab")
		)
		(fp_line
			(start 0.120396 0.3048)
			(end 0.120396 0.2794)
			(stroke
				(width 0.1)
				(type default)
			)
			(layer "F.Fab")
		)
		(fp_line
			(start 0.120396 0.2794)
			(end -0.12065 0.2794)
			(stroke
				(width 0.1)
				(type default)
			)
			(layer "F.Fab")
		)
		(fp_line
			(start -0.12065 0.3048)
			(end -0.67945 0.3048)
			(stroke
				(width 0.1)
				(type default)
			)
			(layer "F.Fab")
		)
		(fp_line
			(start -0.12065 0.2794)
			(end -0.12065 0.3048)
			(stroke
				(width 0.1)
				(type default)
			)
			(layer "F.Fab")
		)
		(fp_line
			(start -0.12065 -0.2794)
			(end 0.12065 -0.2794)
			(stroke
				(width 0.1)
				(type default)
			)
			(layer "F.Fab")
		)
		(fp_line
			(start -0.12065 -0.305054)
			(end -0.12065 -0.2794)
			(stroke
				(width 0.1)
				(type default)
			)
			(layer "F.Fab")
		)
		(fp_line
			(start -0.67945 0.3048)
			(end -0.67945 -0.305054)
			(stroke
				(width 0.1)
				(type default)
			)
			(layer "F.Fab")
		)
		(fp_line
			(start -0.67945 -0.305054)
			(end -0.12065 -0.305054)
			(stroke
				(width 0.1)
				(type default)
			)
			(layer "F.Fab")
		)
		(pad "1" smd circle
			(at -0.40005 0 180)
			(size 0 0)
			(layers "F.Cu" "F.Mask" "F.Paste")
			(net "USB_CPU0_ADD_A0")
		)
		(pad "2" smd circle
			(at 0.40005 0 180)
			(size 0 0)
			(layers "F.Cu" "F.Mask" "F.Paste")
			(net "GND")
		)
	)
)
